(kicad_pcb
	(version 20260206)
	(generator "pcbnew")
	(generator_version "10.0")
	(general
		(thickness 1.6)
		(legacy_teardrops no)
	)
	(paper "A4")
	(title_block
		(title "03242023_DA0F0TMBIJ0_F0T_Motherboard_J_brd_V01_OCP.brd")
		(comment 1 "Grand Teton / footprints 5823-5829 of 6105")
	)
	(layers
		(0 "F.Cu" signal "TOP")
		(4 "In1.Cu" signal "GND")
		(6 "In2.Cu" signal "IN1")
		(8 "In3.Cu" signal "GND1")
		(10 "In4.Cu" signal "IN2")
		(12 "In5.Cu" signal "GND2")
		(14 "In6.Cu" signal "IN3")
		(16 "In7.Cu" signal "GND3")
		(18 "In8.Cu" signal "VCC")
		(20 "In9.Cu" signal "VCC1")
		(22 "In10.Cu" signal "GND4")
		(24 "In11.Cu" signal "IN4")
		(26 "In12.Cu" signal "GND5")
		(28 "In13.Cu" signal "IN5")
		(30 "In14.Cu" signal "GND6")
		(32 "In15.Cu" signal "IN6")
		(34 "In16.Cu" signal "GND7")
		(2 "B.Cu" signal "BOTTOM")
		(9 "F.Adhes" user "F.Adhesive")
		(11 "B.Adhes" user "B.Adhesive")
		(13 "F.Paste" user "Package Geometry/Pastemask Top")
		(15 "B.Paste" user "Package Geometry/Pastemask Bottom")
		(5 "F.SilkS" user "Ref Des/Silkscreen Top")
		(7 "B.SilkS" user "Ref Des/Silkscreen Bottom")
		(1 "F.Mask" user "Board Geometry/Soldermask Top")
		(3 "B.Mask" user "Board Geometry/Soldermask Bottom")
		(17 "Dwgs.User" user "User.Drawings")
		(19 "Cmts.User" user "User.Comments")
		(21 "Eco1.User" user "User.Eco1")
		(23 "Eco2.User" user "User.Eco2")
		(25 "Edge.Cuts" user "Board Geometry/Outline")
		(27 "Margin" user)
		(31 "F.CrtYd" user "Package Geometry/Place Bound Top")
		(29 "B.CrtYd" user "Package Geometry/Place Bound Bottom")
		(35 "F.Fab" user "Ref Des/Assembly Top")
		(33 "B.Fab" user "Ref Des/Assembly Bottom")
	)
	(footprint ""
		(layer "B.Cu")
		(at 36.956238 -131.77774)
		(property "Reference" "R2572"
			(at 0 0 0)
			(layer "B.SilkS")
			(hide yes)
			(effects
				(font
					(size 1.27 1.27)
				)
				(justify mirror)
			)
		)
		(property "Value" ""
			(at 0 0 0)
			(layer "B.Fab")
			(effects
				(font
					(size 1.27 1.27)
				)
				(justify mirror)
			)
		)
		(duplicate_pad_numbers_are_jumpers no)
		(fp_line
			(start -0.7874 -0.4064)
			(end -0.7874 0.4064)
			(stroke
				(width 0.1524)
				(type default)
			)
			(layer "B.SilkS")
		)
		(fp_line
			(start -0.7874 0.4064)
			(end 0.7874 0.4064)
			(stroke
				(width 0.1524)
				(type default)
			)
			(layer "B.SilkS")
		)
		(fp_line
			(start 0.7874 -0.4064)
			(end -0.7874 -0.4064)
			(stroke
				(width 0.1524)
				(type default)
			)
			(layer "B.SilkS")
		)
		(fp_line
			(start 0.7874 0.4064)
			(end 0.7874 -0.4064)
			(stroke
				(width 0.1524)
				(type default)
			)
			(layer "B.SilkS")
		)
		(fp_line
			(start -0.67945 -0.3048)
			(end -0.67945 0.3048)
			(stroke
				(width 0.1)
				(type default)
			)
			(layer "B.Fab")
		)
		(fp_line
			(start -0.67945 0.3048)
			(end -0.120396 0.3048)
			(stroke
				(width 0.1)
				(type default)
			)
			(layer "B.Fab")
		)
		(fp_line
			(start -0.12065 -0.3048)
			(end -0.67945 -0.3048)
			(stroke
				(width 0.1)
				(type default)
			)
			(layer "B.Fab")
		)
		(fp_line
			(start -0.12065 -0.2794)
			(end -0.12065 -0.3048)
			(stroke
				(width 0.1)
				(type default)
			)
			(layer "B.Fab")
		)
		(fp_line
			(start -0.120396 0.2794)
			(end 0.12065 0.2794)
			(stroke
				(width 0.1)
				(type default)
			)
			(layer "B.Fab")
		)
		(fp_line
			(start -0.120396 0.3048)
			(end -0.120396 0.2794)
			(stroke
				(width 0.1)
				(type default)
			)
			(layer "B.Fab")
		)
		(fp_line
			(start 0.12065 -0.305054)
			(end 0.12065 -0.2794)
			(stroke
				(width 0.1)
				(type default)
			)
			(layer "B.Fab")
		)
		(fp_line
			(start 0.12065 -0.2794)
			(end -0.12065 -0.2794)
			(stroke
				(width 0.1)
				(type default)
			)
			(layer "B.Fab")
		)
		(fp_line
			(start 0.12065 0.2794)
			(end 0.12065 0.3048)
			(stroke
				(width 0.1)
				(type default)
			)
			(layer "B.Fab")
		)
		(fp_line
			(start 0.12065 0.3048)
			(end 0.67945 0.3048)
			(stroke
				(width 0.1)
				(type default)
			)
			(layer "B.Fab")
		)
		(fp_line
			(start 0.67945 -0.305054)
			(end 0.12065 -0.305054)
			(stroke
				(width 0.1)
				(type default)
			)
			(layer "B.Fab")
		)
		(fp_line
			(start 0.67945 0.3048)
			(end 0.67945 -0.305054)
			(stroke
				(width 0.1)
				(type default)
			)
			(layer "B.Fab")
		)
		(pad "1" smd circle
			(at 0.40005 0 180)
			(size 0 0)
			(layers "B.Cu" "B.Mask" "B.Paste")
			(net "PWRGD_PVCCFA_EHV_CPU1")
		)
		(pad "2" smd circle
			(at -0.40005 0 180)
			(size 0 0)
			(layers "B.Cu" "B.Mask" "B.Paste")
			(net "PWRGD_PVCCFA_EHV_CPU1_R")
		)
	)
	(footprint ""
		(layer "B.Cu")
		(at 84.974684 -188.035692 90)
		(property "Reference" "R304"
			(at 0 0 90)
			(layer "B.SilkS")
			(hide yes)
			(effects
				(font
					(size 1.27 1.27)
				)
				(justify mirror)
			)
		)
		(property "Value" ""
			(at 0 0 90)
			(layer "B.Fab")
			(effects
				(font
					(size 1.27 1.27)
				)
				(justify mirror)
			)
		)
		(duplicate_pad_numbers_are_jumpers no)
		(fp_line
			(start 0.7874 -0.4064)
			(end -0.7874 -0.4064)
			(stroke
				(width 0.1524)
				(type default)
			)
			(layer "B.SilkS")
		)
		(fp_line
			(start -0.7874 -0.4064)
			(end -0.7874 0.4064)
			(stroke
				(width 0.1524)
				(type default)
			)
			(layer "B.SilkS")
		)
		(fp_line
			(start 0.7874 0.4064)
			(end 0.7874 -0.4064)
			(stroke
				(width 0.1524)
				(type default)
			)
			(layer "B.SilkS")
		)
		(fp_line
			(start -0.7874 0.4064)
			(end 0.7874 0.4064)
			(stroke
				(width 0.1524)
				(type default)
			)
			(layer "B.SilkS")
		)
		(fp_line
			(start 0.67945 -0.305054)
			(end 0.12065 -0.305054)
			(stroke
				(width 0.1)
				(type default)
			)
			(layer "B.Fab")
		)
		(fp_line
			(start 0.12065 -0.305054)
			(end 0.12065 -0.2794)
			(stroke
				(width 0.1)
				(type default)
			)
			(layer "B.Fab")
		)
		(fp_line
			(start -0.12065 -0.3048)
			(end -0.67945 -0.3048)
			(stroke
				(width 0.1)
				(type default)
			)
			(layer "B.Fab")
		)
		(fp_line
			(start -0.67945 -0.3048)
			(end -0.67945 0.3048)
			(stroke
				(width 0.1)
				(type default)
			)
			(layer "B.Fab")
		)
		(fp_line
			(start 0.12065 -0.2794)
			(end -0.12065 -0.2794)
			(stroke
				(width 0.1)
				(type default)
			)
			(layer "B.Fab")
		)
		(fp_line
			(start -0.12065 -0.2794)
			(end -0.12065 -0.3048)
			(stroke
				(width 0.1)
				(type default)
			)
			(layer "B.Fab")
		)
		(fp_line
			(start 0.12065 0.2794)
			(end 0.12065 0.3048)
			(stroke
				(width 0.1)
				(type default)
			)
			(layer "B.Fab")
		)
		(fp_line
			(start -0.120396 0.2794)
			(end 0.12065 0.2794)
			(stroke
				(width 0.1)
				(type default)
			)
			(layer "B.Fab")
		)
		(fp_line
			(start 0.67945 0.3048)
			(end 0.67945 -0.305054)
			(stroke
				(width 0.1)
				(type default)
			)
			(layer "B.Fab")
		)
		(fp_line
			(start 0.12065 0.3048)
			(end 0.67945 0.3048)
			(stroke
				(width 0.1)
				(type default)
			)
			(layer "B.Fab")
		)
		(fp_line
			(start -0.120396 0.3048)
			(end -0.120396 0.2794)
			(stroke
				(width 0.1)
				(type default)
			)
			(layer "B.Fab")
		)
		(fp_line
			(start -0.67945 0.3048)
			(end -0.120396 0.3048)
			(stroke
				(width 0.1)
				(type default)
			)
			(layer "B.Fab")
		)
		(pad "1" smd circle
			(at 0.40005 0 270)
			(size 0 0)
			(layers "B.Cu" "B.Mask" "B.Paste")
			(net "H_CPU1_RMCA_LVC1_R_N")
		)
		(pad "2" smd circle
			(at -0.40005 0 270)
			(size 0 0)
			(layers "B.Cu" "B.Mask" "B.Paste")
			(net "H_CPU_RMCA_LVC1_R_N")
		)
	)
	(footprint ""
		(layer "B.Cu")
		(at 204.088746 -319.268856 180)
		(property "Reference" "C72"
			(at 0 0 0)
			(layer "B.SilkS")
			(hide yes)
			(effects
				(font
					(size 1.27 1.27)
				)
				(justify mirror)
			)
		)
		(property "Value" ""
			(at 0 0 0)
			(layer "B.Fab")
			(effects
				(font
					(size 1.27 1.27)
				)
				(justify mirror)
			)
		)
		(duplicate_pad_numbers_are_jumpers no)
		(fp_line
			(start 0.7874 0.4064)
			(end 0.7874 -0.4064)
			(stroke
				(width 0.1524)
				(type default)
			)
			(layer "B.SilkS")
		)
		(fp_line
			(start 0.7874 -0.4064)
			(end -0.7874 -0.4064)
			(stroke
				(width 0.1524)
				(type default)
			)
			(layer "B.SilkS")
		)
		(fp_line
			(start -0.7874 0.4064)
			(end 0.7874 0.4064)
			(stroke
				(width 0.1524)
				(type default)
			)
			(layer "B.SilkS")
		)
		(fp_line
			(start -0.7874 -0.4064)
			(end -0.7874 0.4064)
			(stroke
				(width 0.1524)
				(type default)
			)
			(layer "B.SilkS")
		)
		(fp_line
			(start 0.67945 0.3048)
			(end 0.67945 -0.305054)
			(stroke
				(width 0.1)
				(type default)
			)
			(layer "B.Fab")
		)
		(fp_line
			(start 0.67945 -0.305054)
			(end 0.12065 -0.305054)
			(stroke
				(width 0.1)
				(type default)
			)
			(layer "B.Fab")
		)
		(fp_line
			(start 0.12065 0.3048)
			(end 0.67945 0.3048)
			(stroke
				(width 0.1)
				(type default)
			)
			(layer "B.Fab")
		)
		(fp_line
			(start 0.12065 0.2794)
			(end 0.12065 0.3048)
			(stroke
				(width 0.1)
				(type default)
			)
			(layer "B.Fab")
		)
		(fp_line
			(start 0.12065 -0.2794)
			(end -0.12065 -0.2794)
			(stroke
				(width 0.1)
				(type default)
			)
			(layer "B.Fab")
		)
		(fp_line
			(start 0.12065 -0.305054)
			(end 0.12065 -0.2794)
			(stroke
				(width 0.1)
				(type default)
			)
			(layer "B.Fab")
		)
		(fp_line
			(start -0.120396 0.3048)
			(end -0.120396 0.2794)
			(stroke
				(width 0.1)
				(type default)
			)
			(layer "B.Fab")
		)
		(fp_line
			(start -0.120396 0.2794)
			(end 0.12065 0.2794)
			(stroke
				(width 0.1)
				(type default)
			)
			(layer "B.Fab")
		)
		(fp_line
			(start -0.12065 -0.2794)
			(end -0.12065 -0.3048)
			(stroke
				(width 0.1)
				(type default)
			)
			(layer "B.Fab")
		)
		(fp_line
			(start -0.12065 -0.3048)
			(end -0.67945 -0.3048)
			(stroke
				(width 0.1)
				(type default)
			)
			(layer "B.Fab")
		)
		(fp_line
			(start -0.67945 0.3048)
			(end -0.120396 0.3048)
			(stroke
				(width 0.1)
				(type default)
			)
			(layer "B.Fab")
		)
		(fp_line
			(start -0.67945 -0.3048)
			(end -0.67945 0.3048)
			(stroke
				(width 0.1)
				(type default)
			)
			(layer "B.Fab")
		)
		(pad "1" smd circle
			(at 0.40005 0)
			(size 0 0)
			(layers "B.Cu" "B.Mask" "B.Paste")
			(net "P3V3_AUX")
		)
		(pad "2" smd circle
			(at -0.40005 0)
			(size 0 0)
			(layers "B.Cu" "B.Mask" "B.Paste")
			(net "GND")
		)
	)
	(footprint ""
		(layer "B.Cu")
		(at 162.889946 -321.554856 -90)
		(property "Reference" "C92"
			(at 0 0 90)
			(layer "B.SilkS")
			(hide yes)
			(effects
				(font
					(size 1.27 1.27)
				)
				(justify mirror)
			)
		)
		(property "Value" ""
			(at 0 0 90)
			(layer "B.Fab")
			(effects
				(font
					(size 1.27 1.27)
				)
				(justify mirror)
			)
		)
		(duplicate_pad_numbers_are_jumpers no)
		(fp_line
			(start -1.524 0.762)
			(end 1.524 0.762)
			(stroke
				(width 0.1524)
				(type default)
			)
			(layer "B.SilkS")
		)
		(fp_line
			(start 1.524 0.762)
			(end 1.524 -0.762)
			(stroke
				(width 0.1524)
				(type default)
			)
			(layer "B.SilkS")
		)
		(fp_line
			(start -1.524 -0.762)
			(end -1.524 0.762)
			(stroke
				(width 0.1524)
				(type default)
			)
			(layer "B.SilkS")
		)
		(fp_line
			(start 1.524 -0.762)
			(end -1.524 -0.762)
			(stroke
				(width 0.1524)
				(type default)
			)
			(layer "B.SilkS")
		)
		(fp_line
			(start -1.1049 0.724916)
			(end -1.1049 -0.724916)
			(stroke
				(width 0.1)
				(type default)
			)
			(layer "B.Fab")
		)
		(fp_line
			(start 1.1049 0.724916)
			(end -1.1049 0.724916)
			(stroke
				(width 0.1)
				(type default)
			)
			(layer "B.Fab")
		)
		(fp_line
			(start -1.1049 -0.724916)
			(end 1.1049 -0.724916)
			(stroke
				(width 0.1)
				(type default)
			)
			(layer "B.Fab")
		)
		(fp_line
			(start 1.1049 -0.724916)
			(end 1.1049 0.724916)
			(stroke
				(width 0.1)
				(type default)
			)
			(layer "B.Fab")
		)
		(pad "1" smd rect
			(at 0.889 0 270)
			(size 1.016 1.27)
			(layers "B.Cu" "B.Mask" "B.Paste")
			(net "P12V_S3_AUX_CPU1_NVDIMM")
		)
		(pad "2" smd rect
			(at -0.889 0 270)
			(size 1.016 1.27)
			(layers "B.Cu" "B.Mask" "B.Paste")
			(net "GND")
		)
	)
	(footprint ""
		(layer "B.Cu")
		(at 176.955704 -112.175544)
		(property "Reference" "C1903"
			(at 0 0 0)
			(layer "B.SilkS")
			(hide yes)
			(effects
				(font
					(size 1.27 1.27)
				)
				(justify mirror)
			)
		)
		(property "Value" ""
			(at 0 0 0)
			(layer "B.Fab")
			(effects
				(font
					(size 1.27 1.27)
				)
				(justify mirror)
			)
		)
		(duplicate_pad_numbers_are_jumpers no)
		(fp_line
			(start -0.69215 -0.2921)
			(end -0.69215 0.2921)
			(stroke
				(width 0.1524)
				(type default)
			)
			(layer "B.SilkS")
		)
		(fp_line
			(start -0.69215 0.2921)
			(end 0.69215 0.2921)
			(stroke
				(width 0.1524)
				(type default)
			)
			(layer "B.SilkS")
		)
		(fp_line
			(start 0.69215 -0.2921)
			(end -0.69215 -0.2921)
			(stroke
				(width 0.1524)
				(type default)
			)
			(layer "B.SilkS")
		)
		(fp_line
			(start 0.69215 0.2921)
			(end 0.69215 -0.2921)
			(stroke
				(width 0.1524)
				(type default)
			)
			(layer "B.SilkS")
		)
		(fp_line
			(start -0.51435 -0.2794)
			(end -0.51435 0.2794)
			(stroke
				(width 0.1)
				(type default)
			)
			(layer "B.Fab")
		)
		(fp_line
			(start -0.51435 0.2794)
			(end 0.51435 0.2794)
			(stroke
				(width 0.1)
				(type default)
			)
			(layer "B.Fab")
		)
		(fp_line
			(start 0.51435 -0.2794)
			(end -0.51435 -0.2794)
			(stroke
				(width 0.1)
				(type default)
			)
			(layer "B.Fab")
		)
		(fp_line
			(start 0.51435 0.2794)
			(end 0.51435 -0.2794)
			(stroke
				(width 0.1)
				(type default)
			)
			(layer "B.Fab")
		)
		(pad "1" smd circle
			(at 0.40005 0 180)
			(size 0 0)
			(layers "B.Cu" "B.Mask" "B.Paste")
			(net "VCC_PLD_CORE")
		)
		(pad "2" smd circle
			(at -0.40005 0 180)
			(size 0 0)
			(layers "B.Cu" "B.Mask" "B.Paste")
			(net "GND")
		)
		(zone
			(layer "B.Cu")
			(hatch none 0.5)
			(connect_pads
				(clearance 0)
			)
			(min_thickness 0.25)
			(keepout
				(tracks not_allowed)
				(vias allowed)
				(pads allowed)
				(copperpour not_allowed)
				(footprints allowed)
			)
			(placement
				(enabled no)
				(sheetname "")
			)
			(fill
				(thermal_gap 0.5)
				(thermal_bridge_width 0.5)
				(island_removal_mode 0)
			)
			(polygon
				(pts
					(xy 177.146204 -112.087914) (xy 177.054764 -112.029748) (xy 176.855374 -112.029748) (xy 176.765204 -112.087914)
					(xy 176.765204 -112.263174) (xy 176.855374 -112.321594) (xy 177.054764 -112.321594) (xy 177.146204 -112.263428)
				)
			)
		)
	)
	(footprint ""
		(layer "B.Cu")
		(at 455.1299 -71.247508 90)
		(property "Reference" "PC571"
			(at 0 0 90)
			(layer "B.SilkS")
			(hide yes)
			(effects
				(font
					(size 1.27 1.27)
				)
				(justify mirror)
			)
		)
		(property "Value" ""
			(at 0 0 90)
			(layer "B.Fab")
			(effects
				(font
					(size 1.27 1.27)
				)
				(justify mirror)
			)
		)
		(duplicate_pad_numbers_are_jumpers no)
		(fp_line
			(start 1.524 -0.762)
			(end -1.524 -0.762)
			(stroke
				(width 0.1524)
				(type default)
			)
			(layer "B.SilkS")
		)
		(fp_line
			(start -1.524 -0.762)
			(end -1.524 0.762)
			(stroke
				(width 0.1524)
				(type default)
			)
			(layer "B.SilkS")
		)
		(fp_line
			(start 1.524 0.762)
			(end 1.524 -0.762)
			(stroke
				(width 0.1524)
				(type default)
			)
			(layer "B.SilkS")
		)
		(fp_line
			(start -1.524 0.762)
			(end 1.524 0.762)
			(stroke
				(width 0.1524)
				(type default)
			)
			(layer "B.SilkS")
		)
		(fp_line
			(start 1.1049 -0.724916)
			(end 1.1049 0.724916)
			(stroke
				(width 0.1)
				(type default)
			)
			(layer "B.Fab")
		)
		(fp_line
			(start -1.1049 -0.724916)
			(end 1.1049 -0.724916)
			(stroke
				(width 0.1)
				(type default)
			)
			(layer "B.Fab")
		)
		(fp_line
			(start 1.1049 0.724916)
			(end -1.1049 0.724916)
			(stroke
				(width 0.1)
				(type default)
			)
			(layer "B.Fab")
		)
		(fp_line
			(start -1.1049 0.724916)
			(end -1.1049 -0.724916)
			(stroke
				(width 0.1)
				(type default)
			)
			(layer "B.Fab")
		)
		(pad "1" smd rect
			(at 0.889 0 90)
			(size 1.016 1.27)
			(layers "B.Cu" "B.Mask" "B.Paste")
			(net "SW_P3V3_AUX_FLT")
		)
		(pad "2" smd rect
			(at -0.889 0 90)
			(size 1.016 1.27)
			(layers "B.Cu" "B.Mask" "B.Paste")
			(net "GND")
		)
	)
	(footprint ""
		(layer "B.Cu")
		(at 334.662018 -188.92647 -90)
		(property "Reference" "R19"
			(at 0 0 90)
			(layer "B.SilkS")
			(hide yes)
			(effects
				(font
					(size 1.27 1.27)
				)
				(justify mirror)
			)
		)
		(property "Value" ""
			(at 0 0 90)
			(layer "B.Fab")
			(effects
				(font
					(size 1.27 1.27)
				)
				(justify mirror)
			)
		)
		(duplicate_pad_numbers_are_jumpers no)
		(fp_line
			(start -0.7874 0.4064)
			(end 0.7874 0.4064)
			(stroke
				(width 0.1524)
				(type default)
			)
			(layer "B.SilkS")
		)
		(fp_line
			(start 0.7874 0.4064)
			(end 0.7874 -0.4064)
			(stroke
				(width 0.1524)
				(type default)
			)
			(layer "B.SilkS")
		)
		(fp_line
			(start -0.7874 -0.4064)
			(end -0.7874 0.4064)
			(stroke
				(width 0.1524)
				(type default)
			)
			(layer "B.SilkS")
		)
		(fp_line
			(start 0.7874 -0.4064)
			(end -0.7874 -0.4064)
			(stroke
				(width 0.1524)
				(type default)
			)
			(layer "B.SilkS")
		)
		(fp_line
			(start -0.67945 0.3048)
			(end -0.120396 0.3048)
			(stroke
				(width 0.1)
				(type default)
			)
			(layer "B.Fab")
		)
		(fp_line
			(start -0.120396 0.3048)
			(end -0.120396 0.2794)
			(stroke
				(width 0.1)
				(type default)
			)
			(layer "B.Fab")
		)
		(fp_line
			(start 0.12065 0.3048)
			(end 0.67945 0.3048)
			(stroke
				(width 0.1)
				(type default)
			)
			(layer "B.Fab")
		)
		(fp_line
			(start 0.67945 0.3048)
			(end 0.67945 -0.305054)
			(stroke
				(width 0.1)
				(type default)
			)
			(layer "B.Fab")
		)
		(fp_line
			(start -0.120396 0.2794)
			(end 0.12065 0.2794)
			(stroke
				(width 0.1)
				(type default)
			)
			(layer "B.Fab")
		)
		(fp_line
			(start 0.12065 0.2794)
			(end 0.12065 0.3048)
			(stroke
				(width 0.1)
				(type default)
			)
			(layer "B.Fab")
		)
		(fp_line
			(start -0.12065 -0.2794)
			(end -0.12065 -0.3048)
			(stroke
				(width 0.1)
				(type default)
			)
			(layer "B.Fab")
		)
		(fp_line
			(start 0.12065 -0.2794)
			(end -0.12065 -0.2794)
			(stroke
				(width 0.1)
				(type default)
			)
			(layer "B.Fab")
		)
		(fp_line
			(start -0.67945 -0.3048)
			(end -0.67945 0.3048)
			(stroke
				(width 0.1)
				(type default)
			)
			(layer "B.Fab")
		)
		(fp_line
			(start -0.12065 -0.3048)
			(end -0.67945 -0.3048)
			(stroke
				(width 0.1)
				(type default)
			)
			(layer "B.Fab")
		)
		(fp_line
			(start 0.12065 -0.305054)
			(end 0.12065 -0.2794)
			(stroke
				(width 0.1)
				(type default)
			)
			(layer "B.Fab")
		)
		(fp_line
			(start 0.67945 -0.305054)
			(end 0.12065 -0.305054)
			(stroke
				(width 0.1)
				(type default)
			)
			(layer "B.Fab")
		)
		(pad "1" smd circle
			(at 0.40005 0 90)
			(size 0 0)
			(layers "B.Cu" "B.Mask" "B.Paste")
			(net "PVNN_TERM_CPU0")
		)
		(pad "2" smd circle
			(at -0.40005 0 90)
			(size 0 0)
			(layers "B.Cu" "B.Mask" "B.Paste")
			(net "DBP_CPU_MBP1_GTL_N")
		)
	)
)
